(kicad_pcb
	(version 20260206)
	(generator "pcbnew")
	(generator_version "10.0")
	(general
		(thickness 1.6)
		(legacy_teardrops no)
	)
	(paper "A4")
	(title_block
		(title "03242023_DA0F0TMBIJ0_F0T_Motherboard_J_brd_V01_OCP.brd")
		(comment 1 "Grand Teton / footprints 2828-2834 of 6105")
	)
	(layers
		(0 "F.Cu" signal "TOP")
		(4 "In1.Cu" signal "GND")
		(6 "In2.Cu" signal "IN1")
		(8 "In3.Cu" signal "GND1")
		(10 "In4.Cu" signal "IN2")
		(12 "In5.Cu" signal "GND2")
		(14 "In6.Cu" signal "IN3")
		(16 "In7.Cu" signal "GND3")
		(18 "In8.Cu" signal "VCC")
		(20 "In9.Cu" signal "VCC1")
		(22 "In10.Cu" signal "GND4")
		(24 "In11.Cu" signal "IN4")
		(26 "In12.Cu" signal "GND5")
		(28 "In13.Cu" signal "IN5")
		(30 "In14.Cu" signal "GND6")
		(32 "In15.Cu" signal "IN6")
		(34 "In16.Cu" signal "GND7")
		(2 "B.Cu" signal "BOTTOM")
		(9 "F.Adhes" user "F.Adhesive")
		(11 "B.Adhes" user "B.Adhesive")
		(13 "F.Paste" user "Package Geometry/Pastemask Top")
		(15 "B.Paste" user "Package Geometry/Pastemask Bottom")
		(5 "F.SilkS" user "Ref Des/Silkscreen Top")
		(7 "B.SilkS" user "Ref Des/Silkscreen Bottom")
		(1 "F.Mask" user "Board Geometry/Soldermask Top")
		(3 "B.Mask" user "Board Geometry/Soldermask Bottom")
		(17 "Dwgs.User" user "User.Drawings")
		(19 "Cmts.User" user "User.Comments")
		(21 "Eco1.User" user "User.Eco1")
		(23 "Eco2.User" user "User.Eco2")
		(25 "Edge.Cuts" user "Board Geometry/Outline")
		(27 "Margin" user)
		(31 "F.CrtYd" user "Package Geometry/Place Bound Top")
		(29 "B.CrtYd" user "Package Geometry/Place Bound Bottom")
		(35 "F.Fab" user "Ref Des/Assembly Top")
		(33 "B.Fab" user "Ref Des/Assembly Bottom")
	)
	(footprint ""
		(layer "F.Cu")
		(at 443.717172 -32.173418 90)
		(property "Reference" "PC2153"
			(at 0 0 90)
			(layer "F.SilkS")
			(hide yes)
			(effects
				(font
					(size 1.27 1.27)
				)
			)
		)
		(property "Value" ""
			(at 0 0 90)
			(layer "F.Fab")
			(effects
				(font
					(size 1.27 1.27)
				)
			)
		)
		(duplicate_pad_numbers_are_jumpers no)
		(fp_line
			(start 0.7874 -0.4064)
			(end 0.7874 0.4064)
			(stroke
				(width 0.1524)
				(type default)
			)
			(layer "F.SilkS")
		)
		(fp_line
			(start -0.7874 -0.4064)
			(end 0.7874 -0.4064)
			(stroke
				(width 0.1524)
				(type default)
			)
			(layer "F.SilkS")
		)
		(fp_line
			(start 0.7874 0.4064)
			(end -0.7874 0.4064)
			(stroke
				(width 0.1524)
				(type default)
			)
			(layer "F.SilkS")
		)
		(fp_line
			(start -0.7874 0.4064)
			(end -0.7874 -0.4064)
			(stroke
				(width 0.1524)
				(type default)
			)
			(layer "F.SilkS")
		)
		(fp_line
			(start -0.12065 -0.305054)
			(end -0.12065 -0.2794)
			(stroke
				(width 0.1)
				(type default)
			)
			(layer "F.Fab")
		)
		(fp_line
			(start -0.67945 -0.305054)
			(end -0.12065 -0.305054)
			(stroke
				(width 0.1)
				(type default)
			)
			(layer "F.Fab")
		)
		(fp_line
			(start 0.67945 -0.3048)
			(end 0.67945 0.3048)
			(stroke
				(width 0.1)
				(type default)
			)
			(layer "F.Fab")
		)
		(fp_line
			(start 0.12065 -0.3048)
			(end 0.67945 -0.3048)
			(stroke
				(width 0.1)
				(type default)
			)
			(layer "F.Fab")
		)
		(fp_line
			(start 0.12065 -0.2794)
			(end 0.12065 -0.3048)
			(stroke
				(width 0.1)
				(type default)
			)
			(layer "F.Fab")
		)
		(fp_line
			(start -0.12065 -0.2794)
			(end 0.12065 -0.2794)
			(stroke
				(width 0.1)
				(type default)
			)
			(layer "F.Fab")
		)
		(fp_line
			(start 0.120396 0.2794)
			(end -0.12065 0.2794)
			(stroke
				(width 0.1)
				(type default)
			)
			(layer "F.Fab")
		)
		(fp_line
			(start -0.12065 0.2794)
			(end -0.12065 0.3048)
			(stroke
				(width 0.1)
				(type default)
			)
			(layer "F.Fab")
		)
		(fp_line
			(start 0.67945 0.3048)
			(end 0.120396 0.3048)
			(stroke
				(width 0.1)
				(type default)
			)
			(layer "F.Fab")
		)
		(fp_line
			(start 0.120396 0.3048)
			(end 0.120396 0.2794)
			(stroke
				(width 0.1)
				(type default)
			)
			(layer "F.Fab")
		)
		(fp_line
			(start -0.12065 0.3048)
			(end -0.67945 0.3048)
			(stroke
				(width 0.1)
				(type default)
			)
			(layer "F.Fab")
		)
		(fp_line
			(start -0.67945 0.3048)
			(end -0.67945 -0.305054)
			(stroke
				(width 0.1)
				(type default)
			)
			(layer "F.Fab")
		)
		(pad "1" smd circle
			(at -0.40005 0 90)
			(size 0 0)
			(layers "F.Cu" "F.Mask" "F.Paste")
			(net "P12V_OCP_TIMER_1")
		)
		(pad "2" smd circle
			(at 0.40005 0 90)
			(size 0 0)
			(layers "F.Cu" "F.Mask" "F.Paste")
			(net "GND")
		)
	)
	(footprint ""
		(layer "F.Cu")
		(at 308.66334 -435.71541 90)
		(property "Reference" "Q131"
			(at 4.467098 -1.20269 0)
			(unlocked yes)
			(layer "F.SilkS")
			(effects
				(font
					(size 0.7874 0.5842)
					(thickness 0.1524)
				)
				(justify left)
			)
		)
		(property "Value" ""
			(at 0 0 90)
			(layer "F.Fab")
			(effects
				(font
					(size 1.27 1.27)
				)
			)
		)
		(duplicate_pad_numbers_are_jumpers no)
		(fp_line
			(start 1.332738 -1.100074)
			(end 1.332738 1.100074)
			(stroke
				(width 0.1524)
				(type default)
			)
			(layer "F.SilkS")
		)
		(fp_line
			(start 0.4826 -1.100074)
			(end 1.332738 -1.100074)
			(stroke
				(width 0.1524)
				(type default)
			)
			(layer "F.SilkS")
		)
		(fp_line
			(start -0.4826 -1.100074)
			(end 0 -0.541274)
			(stroke
				(width 0.1524)
				(type default)
			)
			(layer "F.SilkS")
		)
		(fp_line
			(start -1.332738 -1.100074)
			(end -0.4826 -1.100074)
			(stroke
				(width 0.1524)
				(type default)
			)
			(layer "F.SilkS")
		)
		(fp_line
			(start 0 -0.541274)
			(end 0.4826 -1.100074)
			(stroke
				(width 0.1524)
				(type default)
			)
			(layer "F.SilkS")
		)
		(fp_line
			(start 1.332738 1.100074)
			(end -1.332738 1.100074)
			(stroke
				(width 0.1524)
				(type default)
			)
			(layer "F.SilkS")
		)
		(fp_line
			(start -1.332738 1.100074)
			(end -1.332738 -1.100074)
			(stroke
				(width 0.1524)
				(type default)
			)
			(layer "F.SilkS")
		)
		(fp_poly
			(pts
				(xy -2.43586 -1.303274) (xy -1.733804 -0.952246) (xy -2.43586 -0.601218)
			)
			(stroke
				(width 0)
				(type default)
			)
			(fill yes)
			(layer "F.SilkS")
		)
		(fp_line
			(start 0.674878 -1.100074)
			(end 0.674878 1.100074)
			(stroke
				(width 0.1)
				(type default)
			)
			(layer "F.Fab")
		)
		(fp_line
			(start -0.674878 -1.100074)
			(end 0.674878 -1.100074)
			(stroke
				(width 0.1)
				(type default)
			)
			(layer "F.Fab")
		)
		(fp_line
			(start 0.674878 1.100074)
			(end -0.674878 1.100074)
			(stroke
				(width 0.1)
				(type default)
			)
			(layer "F.Fab")
		)
		(fp_line
			(start -0.674878 1.100074)
			(end -0.674878 -1.100074)
			(stroke
				(width 0.1)
				(type default)
			)
			(layer "F.Fab")
		)
		(fp_poly
			(pts
				(xy -2.2352 -0.298958) (xy -2.2352 -1.001014) (xy -1.533144 -0.649986)
			)
			(stroke
				(width 0)
				(type default)
			)
			(fill yes)
			(layer "F.Fab")
		)
		(pad "1" smd rect
			(at -0.94996 -0.649986 180)
			(size 0.4318 0.508)
			(layers "F.Cu" "F.Mask" "F.Paste")
			(net "GND")
		)
		(pad "2" smd rect
			(at -0.94996 0 180)
			(size 0.4318 0.508)
			(layers "F.Cu" "F.Mask" "F.Paste")
			(net "GPU_3V3IO_RSVD1_FFU")
		)
		(pad "3" smd rect
			(at -0.94996 0.649986 180)
			(size 0.4318 0.508)
			(layers "F.Cu" "F.Mask" "F.Paste")
			(net "GPU_3V3IO_RSVD1_FFU_ISO")
		)
		(pad "4" smd rect
			(at 0.94996 0.649986 180)
			(size 0.4318 0.508)
			(layers "F.Cu" "F.Mask" "F.Paste")
			(net "GND")
		)
		(pad "5" smd rect
			(at 0.94996 0 180)
			(size 0.4318 0.508)
			(layers "F.Cu" "F.Mask" "F.Paste")
			(net "GPU_3V3IO_RSVD1_FFU_N")
		)
		(pad "6" smd rect
			(at 0.94996 -0.649986 180)
			(size 0.4318 0.508)
			(layers "F.Cu" "F.Mask" "F.Paste")
			(net "GPU_3V3IO_RSVD1_FFU_N")
		)
	)
	(footprint ""
		(layer "F.Cu")
		(at 157.430978 -46.741588)
		(property "Reference" "R4487"
			(at 0 0 0)
			(layer "F.SilkS")
			(hide yes)
			(effects
				(font
					(size 1.27 1.27)
				)
			)
		)
		(property "Value" ""
			(at 0 0 0)
			(layer "F.Fab")
			(effects
				(font
					(size 1.27 1.27)
				)
			)
		)
		(duplicate_pad_numbers_are_jumpers no)
		(fp_line
			(start -0.009398 -0.4064)
			(end 0.7874 -0.4064)
			(stroke
				(width 0.1524)
				(type default)
			)
			(layer "F.SilkS")
		)
		(fp_line
			(start 0.7874 -0.4064)
			(end 0.7874 0.4064)
			(stroke
				(width 0.1524)
				(type default)
			)
			(layer "F.SilkS")
		)
		(fp_line
			(start 0.7874 0.4064)
			(end 0.041402 0.4064)
			(stroke
				(width 0.1524)
				(type default)
			)
			(layer "F.SilkS")
		)
		(fp_line
			(start -0.67945 -0.305054)
			(end -0.12065 -0.305054)
			(stroke
				(width 0.1)
				(type default)
			)
			(layer "F.Fab")
		)
		(fp_line
			(start -0.67945 0.3048)
			(end -0.67945 -0.305054)
			(stroke
				(width 0.1)
				(type default)
			)
			(layer "F.Fab")
		)
		(fp_line
			(start -0.12065 -0.305054)
			(end -0.12065 -0.2794)
			(stroke
				(width 0.1)
				(type default)
			)
			(layer "F.Fab")
		)
		(fp_line
			(start -0.12065 -0.2794)
			(end 0.12065 -0.2794)
			(stroke
				(width 0.1)
				(type default)
			)
			(layer "F.Fab")
		)
		(fp_line
			(start -0.12065 0.2794)
			(end -0.12065 0.3048)
			(stroke
				(width 0.1)
				(type default)
			)
			(layer "F.Fab")
		)
		(fp_line
			(start -0.12065 0.3048)
			(end -0.67945 0.3048)
			(stroke
				(width 0.1)
				(type default)
			)
			(layer "F.Fab")
		)
		(fp_line
			(start 0.120396 0.2794)
			(end -0.12065 0.2794)
			(stroke
				(width 0.1)
				(type default)
			)
			(layer "F.Fab")
		)
		(fp_line
			(start 0.120396 0.3048)
			(end 0.120396 0.2794)
			(stroke
				(width 0.1)
				(type default)
			)
			(layer "F.Fab")
		)
		(fp_line
			(start 0.12065 -0.3048)
			(end 0.67945 -0.3048)
			(stroke
				(width 0.1)
				(type default)
			)
			(layer "F.Fab")
		)
		(fp_line
			(start 0.12065 -0.2794)
			(end 0.12065 -0.3048)
			(stroke
				(width 0.1)
				(type default)
			)
			(layer "F.Fab")
		)
		(fp_line
			(start 0.67945 -0.3048)
			(end 0.67945 0.3048)
			(stroke
				(width 0.1)
				(type default)
			)
			(layer "F.Fab")
		)
		(fp_line
			(start 0.67945 0.3048)
			(end 0.120396 0.3048)
			(stroke
				(width 0.1)
				(type default)
			)
			(layer "F.Fab")
		)
		(pad "1" smd circle
			(at -0.40005 0)
			(size 0 0)
			(layers "F.Cu" "F.Mask" "F.Paste")
			(net "USB2_HOST_PCH_0_DN")
		)
		(pad "2" smd circle
			(at 0.40005 0)
			(size 0 0)
			(layers "F.Cu" "F.Mask" "F.Paste")
			(net "GND")
		)
	)
	(footprint ""
		(layer "F.Cu")
		(at 150.93188 -109.819948 -90)
		(property "Reference" "C1841"
			(at 0 0 270)
			(layer "F.SilkS")
			(hide yes)
			(effects
				(font
					(size 1.27 1.27)
				)
			)
		)
		(property "Value" ""
			(at 0 0 270)
			(layer "F.Fab")
			(effects
				(font
					(size 1.27 1.27)
				)
			)
		)
		(duplicate_pad_numbers_are_jumpers no)
		(fp_line
			(start -0.7874 0.4064)
			(end -0.7874 -0.4064)
			(stroke
				(width 0.1524)
				(type default)
			)
			(layer "F.SilkS")
		)
		(fp_line
			(start 0.7874 0.4064)
			(end -0.7874 0.4064)
			(stroke
				(width 0.1524)
				(type default)
			)
			(layer "F.SilkS")
		)
		(fp_line
			(start -0.7874 -0.4064)
			(end 0.7874 -0.4064)
			(stroke
				(width 0.1524)
				(type default)
			)
			(layer "F.SilkS")
		)
		(fp_line
			(start 0.7874 -0.4064)
			(end 0.7874 0.4064)
			(stroke
				(width 0.1524)
				(type default)
			)
			(layer "F.SilkS")
		)
		(fp_line
			(start -0.67945 0.3048)
			(end -0.67945 -0.305054)
			(stroke
				(width 0.1)
				(type default)
			)
			(layer "F.Fab")
		)
		(fp_line
			(start -0.12065 0.3048)
			(end -0.67945 0.3048)
			(stroke
				(width 0.1)
				(type default)
			)
			(layer "F.Fab")
		)
		(fp_line
			(start 0.120396 0.3048)
			(end 0.120396 0.2794)
			(stroke
				(width 0.1)
				(type default)
			)
			(layer "F.Fab")
		)
		(fp_line
			(start 0.67945 0.3048)
			(end 0.120396 0.3048)
			(stroke
				(width 0.1)
				(type default)
			)
			(layer "F.Fab")
		)
		(fp_line
			(start -0.12065 0.2794)
			(end -0.12065 0.3048)
			(stroke
				(width 0.1)
				(type default)
			)
			(layer "F.Fab")
		)
		(fp_line
			(start 0.120396 0.2794)
			(end -0.12065 0.2794)
			(stroke
				(width 0.1)
				(type default)
			)
			(layer "F.Fab")
		)
		(fp_line
			(start -0.12065 -0.2794)
			(end 0.12065 -0.2794)
			(stroke
				(width 0.1)
				(type default)
			)
			(layer "F.Fab")
		)
		(fp_line
			(start 0.12065 -0.2794)
			(end 0.12065 -0.3048)
			(stroke
				(width 0.1)
				(type default)
			)
			(layer "F.Fab")
		)
		(fp_line
			(start 0.12065 -0.3048)
			(end 0.67945 -0.3048)
			(stroke
				(width 0.1)
				(type default)
			)
			(layer "F.Fab")
		)
		(fp_line
			(start 0.67945 -0.3048)
			(end 0.67945 0.3048)
			(stroke
				(width 0.1)
				(type default)
			)
			(layer "F.Fab")
		)
		(fp_line
			(start -0.67945 -0.305054)
			(end -0.12065 -0.305054)
			(stroke
				(width 0.1)
				(type default)
			)
			(layer "F.Fab")
		)
		(fp_line
			(start -0.12065 -0.305054)
			(end -0.12065 -0.2794)
			(stroke
				(width 0.1)
				(type default)
			)
			(layer "F.Fab")
		)
		(pad "1" smd circle
			(at -0.40005 0 270)
			(size 0 0)
			(layers "F.Cu" "F.Mask" "F.Paste")
			(net "P3V3_AUX")
		)
		(pad "2" smd circle
			(at 0.40005 0 270)
			(size 0 0)
			(layers "F.Cu" "F.Mask" "F.Paste")
			(net "GND")
		)
	)
	(footprint ""
		(layer "F.Cu")
		(at 390.992106 -78.863698 180)
		(property "Reference" "PC1651"
			(at 0 0 180)
			(layer "F.SilkS")
			(hide yes)
			(effects
				(font
					(size 1.27 1.27)
				)
			)
		)
		(property "Value" ""
			(at 0 0 180)
			(layer "F.Fab")
			(effects
				(font
					(size 1.27 1.27)
				)
			)
		)
		(duplicate_pad_numbers_are_jumpers no)
		(fp_line
			(start 0.7874 0.4064)
			(end -0.7874 0.4064)
			(stroke
				(width 0.1524)
				(type default)
			)
			(layer "F.SilkS")
		)
		(fp_line
			(start 0.7874 -0.4064)
			(end 0.7874 0.4064)
			(stroke
				(width 0.1524)
				(type default)
			)
			(layer "F.SilkS")
		)
		(fp_line
			(start -0.7874 0.4064)
			(end -0.7874 -0.4064)
			(stroke
				(width 0.1524)
				(type default)
			)
			(layer "F.SilkS")
		)
		(fp_line
			(start -0.7874 -0.4064)
			(end 0.7874 -0.4064)
			(stroke
				(width 0.1524)
				(type default)
			)
			(layer "F.SilkS")
		)
		(fp_line
			(start 0.67945 0.3048)
			(end 0.120396 0.3048)
			(stroke
				(width 0.1)
				(type default)
			)
			(layer "F.Fab")
		)
		(fp_line
			(start 0.67945 -0.3048)
			(end 0.67945 0.3048)
			(stroke
				(width 0.1)
				(type default)
			)
			(layer "F.Fab")
		)
		(fp_line
			(start 0.12065 -0.2794)
			(end 0.12065 -0.3048)
			(stroke
				(width 0.1)
				(type default)
			)
			(layer "F.Fab")
		)
		(fp_line
			(start 0.12065 -0.3048)
			(end 0.67945 -0.3048)
			(stroke
				(width 0.1)
				(type default)
			)
			(layer "F.Fab")
		)
		(fp_line
			(start 0.120396 0.3048)
			(end 0.120396 0.2794)
			(stroke
				(width 0.1)
				(type default)
			)
			(layer "F.Fab")
		)
		(fp_line
			(start 0.120396 0.2794)
			(end -0.12065 0.2794)
			(stroke
				(width 0.1)
				(type default)
			)
			(layer "F.Fab")
		)
		(fp_line
			(start -0.12065 0.3048)
			(end -0.67945 0.3048)
			(stroke
				(width 0.1)
				(type default)
			)
			(layer "F.Fab")
		)
		(fp_line
			(start -0.12065 0.2794)
			(end -0.12065 0.3048)
			(stroke
				(width 0.1)
				(type default)
			)
			(layer "F.Fab")
		)
		(fp_line
			(start -0.12065 -0.2794)
			(end 0.12065 -0.2794)
			(stroke
				(width 0.1)
				(type default)
			)
			(layer "F.Fab")
		)
		(fp_line
			(start -0.12065 -0.305054)
			(end -0.12065 -0.2794)
			(stroke
				(width 0.1)
				(type default)
			)
			(layer "F.Fab")
		)
		(fp_line
			(start -0.67945 0.3048)
			(end -0.67945 -0.305054)
			(stroke
				(width 0.1)
				(type default)
			)
			(layer "F.Fab")
		)
		(fp_line
			(start -0.67945 -0.305054)
			(end -0.12065 -0.305054)
			(stroke
				(width 0.1)
				(type default)
			)
			(layer "F.Fab")
		)
		(pad "1" smd circle
			(at -0.40005 0 180)
			(size 0 0)
			(layers "F.Cu" "F.Mask" "F.Paste")
			(net "P12V_AUX")
		)
		(pad "2" smd circle
			(at 0.40005 0 180)
			(size 0 0)
			(layers "F.Cu" "F.Mask" "F.Paste")
			(net "GND")
		)
	)
	(footprint ""
		(layer "F.Cu")
		(at 228.31044 -365.940848)
		(property "Reference" "ME21"
			(at 0 0 0)
			(layer "F.SilkS")
			(hide yes)
			(effects
				(font
					(size 1.27 1.27)
				)
			)
		)
		(property "Value" ""
			(at 0 0 0)
			(layer "F.Fab")
			(effects
				(font
					(size 1.27 1.27)
				)
			)
		)
		(duplicate_pad_numbers_are_jumpers no)
	)
	(footprint ""
		(layer "F.Cu")
		(at 392.03757 -408.517344 -90)
		(property "Reference" "C883"
			(at 0 0 270)
			(layer "F.SilkS")
			(hide yes)
			(effects
				(font
					(size 1.27 1.27)
				)
			)
		)
		(property "Value" ""
			(at 0 0 270)
			(layer "F.Fab")
			(effects
				(font
					(size 1.27 1.27)
				)
			)
		)
		(duplicate_pad_numbers_are_jumpers no)
		(fp_line
			(start -0.299974 0.150114)
			(end -0.299974 -0.150114)
			(stroke
				(width 0.1)
				(type default)
			)
			(layer "F.Fab")
		)
		(fp_line
			(start 0.299974 0.150114)
			(end -0.299974 0.150114)
			(stroke
				(width 0.1)
				(type default)
			)
			(layer "F.Fab")
		)
		(fp_line
			(start -0.299974 -0.150114)
			(end 0.299974 -0.150114)
			(stroke
				(width 0.1)
				(type default)
			)
			(layer "F.Fab")
		)
		(fp_line
			(start 0.299974 -0.150114)
			(end 0.299974 0.150114)
			(stroke
				(width 0.1)
				(type default)
			)
			(layer "F.Fab")
		)
		(pad "1" smd rect
			(at -0.2667 0 270)
			(size 0.3048 0.381)
			(layers "F.Cu" "F.Mask" "F.Paste")
			(net "P5E_CPU0_PE3_TX_C_DP<9>")
		)
		(pad "2" smd rect
			(at 0.2667 0 270)
			(size 0.3048 0.381)
			(layers "F.Cu" "F.Mask" "F.Paste")
			(net "P5E_CPU0_PE3_TX_DP<9>")
		)
	)
)
